# T6G (Grand Teton) — schematic netlist excerpt (pin names and nets, part order shuffled) for the footprints in the layout excerpt that follows; sources: Cadence DE-HDL packaged netlist, KiCad conversion of 04192023_DAF0TMB3IC0_F0TG_MB_C_brd_V02_OCP.brd

R944  Q_RES  4.7K 5% CHIP  pkg 0402LF  page 166 : A = P3V3_AUX ; B = BOOT_RDY_BUF_LED
R3178  Q_RES  0 5% CHIP  pkg 0402LF  page 137 : A = USB2_P10_DP ; B = USB2_CPU0_P10_DP

(kicad_pcb
	(version 20260206)
	(generator "pcbnew")
	(generator_version "10.0")
	(general
		(thickness 1.6)
		(legacy_teardrops no)
	)
	(paper "A4")
	(title_block
		(title "04192023_DAF0TMB3IC0_F0TG_MB_C_brd_V02_OCP.brd")
		(comment 1 "Grand Teton / footprints 2871-2872 of 8354")
	)
	(layers
		(0 "F.Cu" signal "TOP")
		(4 "In1.Cu" signal "GND")
		(6 "In2.Cu" signal "IN1")
		(8 "In3.Cu" signal "GND1")
		(10 "In4.Cu" signal "IN2")
		(12 "In5.Cu" signal "GND2")
		(14 "In6.Cu" signal "IN3")
		(16 "In7.Cu" signal "GND3")
		(18 "In8.Cu" signal "VCC")
		(20 "In9.Cu" signal "VCC1")
		(22 "In10.Cu" signal "GND4")
		(24 "In11.Cu" signal "IN4")
		(26 "In12.Cu" signal "GND5")
		(28 "In13.Cu" signal "IN5")
		(30 "In14.Cu" signal "GND6")
		(32 "In15.Cu" signal "IN6")
		(34 "In16.Cu" signal "GND7")
		(2 "B.Cu" signal "BOTTOM")
		(9 "F.Adhes" user "F.Adhesive")
		(11 "B.Adhes" user "B.Adhesive")
		(13 "F.Paste" user "Package Geometry/Pastemask Top")
		(15 "B.Paste" user "Package Geometry/Pastemask Bottom")
		(5 "F.SilkS" user "Ref Des/Silkscreen Top")
		(7 "B.SilkS" user "Ref Des/Silkscreen Bottom")
		(1 "F.Mask" user "Board Geometry/Soldermask Top")
		(3 "B.Mask" user "Board Geometry/Soldermask Bottom")
		(17 "Dwgs.User" user "User.Drawings")
		(19 "Cmts.User" user "User.Comments")
		(21 "Eco1.User" user "User.Eco1")
		(23 "Eco2.User" user "User.Eco2")
		(25 "Edge.Cuts" user "Board Geometry/Outline")
		(27 "Margin" user)
		(31 "F.CrtYd" user "Package Geometry/Place Bound Top")
		(29 "B.CrtYd" user "Package Geometry/Place Bound Bottom")
		(35 "F.Fab" user "Ref Des/Assembly Top")
		(33 "B.Fab" user "Ref Des/Assembly Bottom")
	)
	(footprint ""
		(layer "F.Cu")
		(at 13.872464 -15.32128 90)
		(property "Reference" "R3178"
			(at 0 0 90)
			(layer "F.SilkS")
			(hide yes)
			(effects
				(font
					(size 1.27 1.27)
				)
			)
		)
		(property "Value" ""
			(at 0 0 90)
			(layer "F.Fab")
			(effects
				(font
					(size 1.27 1.27)
				)
			)
		)
		(duplicate_pad_numbers_are_jumpers no)
		(fp_line
			(start 0.7874 -0.4064)
			(end 0.7874 0.4064)
			(stroke
				(width 0.1524)
				(type default)
			)
			(layer "F.SilkS")
		)
		(fp_line
			(start -0.7874 -0.4064)
			(end 0.7874 -0.4064)
			(stroke
				(width 0.1524)
				(type default)
			)
			(layer "F.SilkS")
		)
		(fp_line
			(start 0.7874 0.4064)
			(end -0.7874 0.4064)
			(stroke
				(width 0.1524)
				(type default)
			)
			(layer "F.SilkS")
		)
		(fp_line
			(start -0.7874 0.4064)
			(end -0.7874 -0.4064)
			(stroke
				(width 0.1524)
				(type default)
			)
			(layer "F.SilkS")
		)
		(fp_line
			(start -0.12065 -0.305054)
			(end -0.12065 -0.2794)
			(stroke
				(width 0.1)
				(type default)
			)
			(layer "F.Fab")
		)
		(fp_line
			(start -0.67945 -0.305054)
			(end -0.12065 -0.305054)
			(stroke
				(width 0.1)
				(type default)
			)
			(layer "F.Fab")
		)
		(fp_line
			(start 0.67945 -0.3048)
			(end 0.67945 0.3048)
			(stroke
				(width 0.1)
				(type default)
			)
			(layer "F.Fab")
		)
		(fp_line
			(start 0.12065 -0.3048)
			(end 0.67945 -0.3048)
			(stroke
				(width 0.1)
				(type default)
			)
			(layer "F.Fab")
		)
		(fp_line
			(start 0.12065 -0.2794)
			(end 0.12065 -0.3048)
			(stroke
				(width 0.1)
				(type default)
			)
			(layer "F.Fab")
		)
		(fp_line
			(start -0.12065 -0.2794)
			(end 0.12065 -0.2794)
			(stroke
				(width 0.1)
				(type default)
			)
			(layer "F.Fab")
		)
		(fp_line
			(start 0.120396 0.2794)
			(end -0.12065 0.2794)
			(stroke
				(width 0.1)
				(type default)
			)
			(layer "F.Fab")
		)
		(fp_line
			(start -0.12065 0.2794)
			(end -0.12065 0.3048)
			(stroke
				(width 0.1)
				(type default)
			)
			(layer "F.Fab")
		)
		(fp_line
			(start 0.67945 0.3048)
			(end 0.120396 0.3048)
			(stroke
				(width 0.1)
				(type default)
			)
			(layer "F.Fab")
		)
		(fp_line
			(start 0.120396 0.3048)
			(end 0.120396 0.2794)
			(stroke
				(width 0.1)
				(type default)
			)
			(layer "F.Fab")
		)
		(fp_line
			(start -0.12065 0.3048)
			(end -0.67945 0.3048)
			(stroke
				(width 0.1)
				(type default)
			)
			(layer "F.Fab")
		)
		(fp_line
			(start -0.67945 0.3048)
			(end -0.67945 -0.305054)
			(stroke
				(width 0.1)
				(type default)
			)
			(layer "F.Fab")
		)
		(pad "1" smd circle
			(at -0.40005 0 90)
			(size 0 0)
			(layers "F.Cu" "F.Mask" "F.Paste")
			(net "USB2_P10_DP")
		)
		(pad "2" smd circle
			(at 0.40005 0 90)
			(size 0 0)
			(layers "F.Cu" "F.Mask" "F.Paste")
			(net "USB2_CPU0_P10_DP")
		)
	)
	(footprint ""
		(layer "F.Cu")
		(at 340.715346 -23.897336 -90)
		(property "Reference" "R944"
			(at 0 0 270)
			(layer "F.SilkS")
			(hide yes)
			(effects
				(font
					(size 1.27 1.27)
				)
			)
		)
		(property "Value" ""
			(at 0 0 270)
			(layer "F.Fab")
			(effects
				(font
					(size 1.27 1.27)
				)
			)
		)
		(duplicate_pad_numbers_are_jumpers no)
		(fp_line
			(start -0.7874 0.4064)
			(end -0.7874 -0.4064)
			(stroke
				(width 0.1524)
				(type default)
			)
			(layer "F.SilkS")
		)
		(fp_line
			(start 0.7874 0.4064)
			(end -0.7874 0.4064)
			(stroke
				(width 0.1524)
				(type default)
			)
			(layer "F.SilkS")
		)
		(fp_line
			(start -0.7874 -0.4064)
			(end 0.7874 -0.4064)
			(stroke
				(width 0.1524)
				(type default)
			)
			(layer "F.SilkS")
		)
		(fp_line
			(start 0.7874 -0.4064)
			(end 0.7874 0.4064)
			(stroke
				(width 0.1524)
				(type default)
			)
			(layer "F.SilkS")
		)
		(fp_line
			(start -0.67945 0.3048)
			(end -0.67945 -0.305054)
			(stroke
				(width 0.1)
				(type default)
			)
			(layer "F.Fab")
		)
		(fp_line
			(start -0.12065 0.3048)
			(end -0.67945 0.3048)
			(stroke
				(width 0.1)
				(type default)
			)
			(layer "F.Fab")
		)
		(fp_line
			(start 0.120396 0.3048)
			(end 0.120396 0.2794)
			(stroke
				(width 0.1)
				(type default)
			)
			(layer "F.Fab")
		)
		(fp_line
			(start 0.67945 0.3048)
			(end 0.120396 0.3048)
			(stroke
				(width 0.1)
				(type default)
			)
			(layer "F.Fab")
		)
		(fp_line
			(start -0.12065 0.2794)
			(end -0.12065 0.3048)
			(stroke
				(width 0.1)
				(type default)
			)
			(layer "F.Fab")
		)
		(fp_line
			(start 0.120396 0.2794)
			(end -0.12065 0.2794)
			(stroke
				(width 0.1)
				(type default)
			)
			(layer "F.Fab")
		)
		(fp_line
			(start -0.12065 -0.2794)
			(end 0.12065 -0.2794)
			(stroke
				(width 0.1)
				(type default)
			)
			(layer "F.Fab")
		)
		(fp_line
			(start 0.12065 -0.2794)
			(end 0.12065 -0.3048)
			(stroke
				(width 0.1)
				(type default)
			)
			(layer "F.Fab")
		)
		(fp_line
			(start 0.12065 -0.3048)
			(end 0.67945 -0.3048)
			(stroke
				(width 0.1)
				(type default)
			)
			(layer "F.Fab")
		)
		(fp_line
			(start 0.67945 -0.3048)
			(end 0.67945 0.3048)
			(stroke
				(width 0.1)
				(type default)
			)
			(layer "F.Fab")
		)
		(fp_line
			(start -0.67945 -0.305054)
			(end -0.12065 -0.305054)
			(stroke
				(width 0.1)
				(type default)
			)
			(layer "F.Fab")
		)
		(fp_line
			(start -0.12065 -0.305054)
			(end -0.12065 -0.2794)
			(stroke
				(width 0.1)
				(type default)
			)
			(layer "F.Fab")
		)
		(pad "1" smd circle
			(at -0.40005 0 270)
			(size 0 0)
			(layers "F.Cu" "F.Mask" "F.Paste")
			(net "P3V3_AUX")
		)
		(pad "2" smd circle
			(at 0.40005 0 270)
			(size 0 0)
			(layers "F.Cu" "F.Mask" "F.Paste")
			(net "BOOT_RDY_BUF_LED")
		)
	)
)
